# SCM (Grand Teton) — schematic netlist excerpt (pin names and nets, part order shuffled) for the footprints in the layout excerpt that follows; sources: Cadence DE-HDL packaged netlist, KiCad conversion of 12092022_DA0F0TMDCD0_F0T_Management_Board_D_brd_V3_OCP.brd

C148  Q_CAP  0.1UF 25V 10% X7R  pkg 0402  page 29 : A = P3V3_AUX ; B = GND
C123  Q_CAP  22UF 6.3V 20% X6S  pkg C0603  page 16 : A = P1V0_AUX ; B = GND

(kicad_pcb
	(version 20260206)
	(generator "pcbnew")
	(generator_version "10.0")
	(general
		(thickness 1.6)
		(legacy_teardrops no)
	)
	(paper "A4")
	(title_block
		(title "12092022_DA0F0TMDCD0_F0T_Management_Board_D_brd_V3_OCP.brd")
		(comment 1 "Grand Teton / footprints 823-824 of 1440")
	)
	(layers
		(0 "F.Cu" signal "TOP")
		(4 "In1.Cu" signal "GND")
		(6 "In2.Cu" signal "IN1")
		(8 "In3.Cu" signal "GND1")
		(10 "In4.Cu" signal "IN2")
		(12 "In5.Cu" signal "VCC")
		(14 "In6.Cu" signal "VCC1")
		(16 "In7.Cu" signal "IN3")
		(18 "In8.Cu" signal "GND2")
		(20 "In9.Cu" signal "IN4")
		(22 "In10.Cu" signal "GND3")
		(2 "B.Cu" signal "BOTTOM")
		(9 "F.Adhes" user "F.Adhesive")
		(11 "B.Adhes" user "B.Adhesive")
		(13 "F.Paste" user "Package Geometry/Pastemask Top")
		(15 "B.Paste" user "Package Geometry/Pastemask Bottom")
		(5 "F.SilkS" user "Ref Des/Silkscreen Top")
		(7 "B.SilkS" user "Ref Des/Silkscreen Bottom")
		(1 "F.Mask" user "Board Geometry/Soldermask Top")
		(3 "B.Mask" user "Board Geometry/Soldermask Bottom")
		(17 "Dwgs.User" user "User.Drawings")
		(19 "Cmts.User" user "User.Comments")
		(21 "Eco1.User" user "User.Eco1")
		(23 "Eco2.User" user "User.Eco2")
		(25 "Edge.Cuts" user "Board Geometry/Outline")
		(27 "Margin" user)
		(31 "F.CrtYd" user "Package Geometry/Place Bound Top")
		(29 "B.CrtYd" user "Package Geometry/Place Bound Bottom")
		(35 "F.Fab" user "Ref Des/Assembly Top")
		(33 "B.Fab" user "Ref Des/Assembly Bottom")
	)
	(footprint ""
		(layer "B.Cu")
		(at 76.239878 -55.895748 -90)
		(property "Reference" "C123"
			(at 0 0 90)
			(layer "B.SilkS")
			(hide yes)
			(effects
				(font
					(size 1.27 1.27)
				)
				(justify mirror)
			)
		)
		(property "Value" ""
			(at 0 0 90)
			(layer "B.Fab")
			(effects
				(font
					(size 1.27 1.27)
				)
				(justify mirror)
			)
		)
		(duplicate_pad_numbers_are_jumpers no)
		(fp_line
			(start -1.2954 0.5842)
			(end 1.2954 0.5842)
			(stroke
				(width 0.1524)
				(type default)
			)
			(layer "B.SilkS")
		)
		(fp_line
			(start 1.2954 0.5842)
			(end 1.2954 -0.5842)
			(stroke
				(width 0.1524)
				(type default)
			)
			(layer "B.SilkS")
		)
		(fp_line
			(start -1.2954 -0.5842)
			(end -1.2954 0.5842)
			(stroke
				(width 0.1524)
				(type default)
			)
			(layer "B.SilkS")
		)
		(fp_line
			(start 0 -0.5842)
			(end 0 0.5842)
			(stroke
				(width 0.1524)
				(type default)
			)
			(layer "B.SilkS")
		)
		(fp_line
			(start 1.2954 -0.5842)
			(end -1.2954 -0.5842)
			(stroke
				(width 0.1524)
				(type default)
			)
			(layer "B.SilkS")
		)
		(fp_line
			(start -0.8636 0.4572)
			(end 0.8636 0.4572)
			(stroke
				(width 0.1)
				(type default)
			)
			(layer "B.Fab")
		)
		(fp_line
			(start 0.8636 0.4572)
			(end 0.8636 0.4064)
			(stroke
				(width 0.1)
				(type default)
			)
			(layer "B.Fab")
		)
		(fp_line
			(start -1.1938 0.4064)
			(end -0.8636 0.4064)
			(stroke
				(width 0.1)
				(type default)
			)
			(layer "B.Fab")
		)
		(fp_line
			(start -0.8636 0.4064)
			(end -0.8636 0.4572)
			(stroke
				(width 0.1)
				(type default)
			)
			(layer "B.Fab")
		)
		(fp_line
			(start 0.8636 0.4064)
			(end 1.1938 0.4064)
			(stroke
				(width 0.1)
				(type default)
			)
			(layer "B.Fab")
		)
		(fp_line
			(start 1.1938 0.4064)
			(end 1.1938 -0.4064)
			(stroke
				(width 0.1)
				(type default)
			)
			(layer "B.Fab")
		)
		(fp_line
			(start -1.1938 -0.4064)
			(end -1.1938 0.4064)
			(stroke
				(width 0.1)
				(type default)
			)
			(layer "B.Fab")
		)
		(fp_line
			(start -0.8636 -0.4064)
			(end -1.1938 -0.4064)
			(stroke
				(width 0.1)
				(type default)
			)
			(layer "B.Fab")
		)
		(fp_line
			(start 0.8636 -0.4064)
			(end 0.8636 -0.4572)
			(stroke
				(width 0.1)
				(type default)
			)
			(layer "B.Fab")
		)
		(fp_line
			(start 1.1938 -0.4064)
			(end 0.8636 -0.4064)
			(stroke
				(width 0.1)
				(type default)
			)
			(layer "B.Fab")
		)
		(fp_line
			(start -0.8636 -0.4572)
			(end -0.8636 -0.4064)
			(stroke
				(width 0.1)
				(type default)
			)
			(layer "B.Fab")
		)
		(fp_line
			(start 0.8636 -0.4572)
			(end -0.8636 -0.4572)
			(stroke
				(width 0.1)
				(type default)
			)
			(layer "B.Fab")
		)
		(pad "1" smd rect
			(at 0.7366 0 180)
			(size 0.7112 0.8128)
			(layers "B.Cu" "B.Mask" "B.Paste")
			(net "P1V0_AUX")
		)
		(pad "2" smd rect
			(at -0.7366 0 180)
			(size 0.7112 0.8128)
			(layers "B.Cu" "B.Mask" "B.Paste")
			(net "GND")
		)
	)
	(footprint ""
		(layer "B.Cu")
		(at 59.309 -24.257 -90)
		(property "Reference" "C148"
			(at 0 0 90)
			(layer "B.SilkS")
			(hide yes)
			(effects
				(font
					(size 1.27 1.27)
				)
				(justify mirror)
			)
		)
		(property "Value" ""
			(at 0 0 90)
			(layer "B.Fab")
			(effects
				(font
					(size 1.27 1.27)
				)
				(justify mirror)
			)
		)
		(duplicate_pad_numbers_are_jumpers no)
		(fp_line
			(start -0.7874 0.4064)
			(end 0.7874 0.4064)
			(stroke
				(width 0.1524)
				(type default)
			)
			(layer "B.SilkS")
		)
		(fp_line
			(start 0.7874 0.4064)
			(end 0.7874 -0.4064)
			(stroke
				(width 0.1524)
				(type default)
			)
			(layer "B.SilkS")
		)
		(fp_line
			(start -0.7874 -0.4064)
			(end -0.7874 0.4064)
			(stroke
				(width 0.1524)
				(type default)
			)
			(layer "B.SilkS")
		)
		(fp_line
			(start 0.7874 -0.4064)
			(end -0.7874 -0.4064)
			(stroke
				(width 0.1524)
				(type default)
			)
			(layer "B.SilkS")
		)
		(fp_line
			(start -0.67945 0.3048)
			(end -0.120396 0.3048)
			(stroke
				(width 0.1)
				(type default)
			)
			(layer "B.Fab")
		)
		(fp_line
			(start -0.120396 0.3048)
			(end -0.120396 0.2794)
			(stroke
				(width 0.1)
				(type default)
			)
			(layer "B.Fab")
		)
		(fp_line
			(start 0.12065 0.3048)
			(end 0.67945 0.3048)
			(stroke
				(width 0.1)
				(type default)
			)
			(layer "B.Fab")
		)
		(fp_line
			(start 0.67945 0.3048)
			(end 0.67945 -0.305054)
			(stroke
				(width 0.1)
				(type default)
			)
			(layer "B.Fab")
		)
		(fp_line
			(start -0.120396 0.2794)
			(end 0.12065 0.2794)
			(stroke
				(width 0.1)
				(type default)
			)
			(layer "B.Fab")
		)
		(fp_line
			(start 0.12065 0.2794)
			(end 0.12065 0.3048)
			(stroke
				(width 0.1)
				(type default)
			)
			(layer "B.Fab")
		)
		(fp_line
			(start -0.12065 -0.2794)
			(end -0.12065 -0.3048)
			(stroke
				(width 0.1)
				(type default)
			)
			(layer "B.Fab")
		)
		(fp_line
			(start 0.12065 -0.2794)
			(end -0.12065 -0.2794)
			(stroke
				(width 0.1)
				(type default)
			)
			(layer "B.Fab")
		)
		(fp_line
			(start -0.67945 -0.3048)
			(end -0.67945 0.3048)
			(stroke
				(width 0.1)
				(type default)
			)
			(layer "B.Fab")
		)
		(fp_line
			(start -0.12065 -0.3048)
			(end -0.67945 -0.3048)
			(stroke
				(width 0.1)
				(type default)
			)
			(layer "B.Fab")
		)
		(fp_line
			(start 0.12065 -0.305054)
			(end 0.12065 -0.2794)
			(stroke
				(width 0.1)
				(type default)
			)
			(layer "B.Fab")
		)
		(fp_line
			(start 0.67945 -0.305054)
			(end 0.12065 -0.305054)
			(stroke
				(width 0.1)
				(type default)
			)
			(layer "B.Fab")
		)
		(pad "1" smd circle
			(at 0.40005 0 90)
			(size 0 0)
			(layers "B.Cu" "B.Mask" "B.Paste")
			(net "P3V3_AUX")
		)
		(pad "2" smd circle
			(at -0.40005 0 90)
			(size 0 0)
			(layers "B.Cu" "B.Mask" "B.Paste")
			(net "GND")
		)
	)
)
